# TIMECARD (Time Appliance Project (Time Card)) — schematic netlist excerpt (pin names and nets, part order shuffled) for the footprints in the layout excerpt that follows; sources: Cadence DE-HDL packaged netlist, KiCad conversion of R4006-B0001-02_R01.brd

R307  RESISTOR  1KOHM 1%  pkg SMC_0402R_H016  page 20 : \1\ = UNNAMED_9_BNO080LGA28_I29_CLKSE ; \2\ = SG
C187  CAPACITOR  0.1UF 25V 10%  pkg SMC_0402R_H022  page 30 : \1\ = XP1R8V_EN_R ; \2\ = SG

(kicad_pcb
	(version 20260206)
	(generator "pcbnew")
	(generator_version "10.0")
	(general
		(thickness 1.6)
		(legacy_teardrops no)
	)
	(paper "A4")
	(title_block
		(title "timecard-production-celestica-r4006 — R4006-B0001-02_R01.brd")
		(comment 1 "Time Appliance Project (Time Card) / footprints 494-495 of 1113")
	)
	(layers
		(0 "F.Cu" signal "TOP")
		(4 "In1.Cu" signal "L02_GND1")
		(6 "In2.Cu" signal "L03_SIG1")
		(8 "In3.Cu" signal "L04_GND2")
		(10 "In4.Cu" signal "L05_VCC1")
		(12 "In5.Cu" signal "L06_VCC2")
		(14 "In6.Cu" signal "L07_GND3")
		(16 "In7.Cu" signal "L08_SIG2")
		(18 "In8.Cu" signal "L09_GND4")
		(2 "B.Cu" signal "BOTTOM")
		(9 "F.Adhes" user "F.Adhesive")
		(11 "B.Adhes" user "B.Adhesive")
		(13 "F.Paste" user "Package Geometry/Pastemask Top")
		(15 "B.Paste" user "Package Geometry/Pastemask Bottom")
		(5 "F.SilkS" user "Ref Des/Silkscreen Top")
		(7 "B.SilkS" user "Ref Des/Silkscreen Bottom")
		(1 "F.Mask" user "Board Geometry/Soldermask Top")
		(3 "B.Mask" user "Board Geometry/Soldermask Bottom")
		(17 "Dwgs.User" user "User.Drawings")
		(19 "Cmts.User" user "User.Comments")
		(21 "Eco1.User" user "User.Eco1")
		(23 "Eco2.User" user "User.Eco2")
		(25 "Edge.Cuts" user "Board Geometry/Outline")
		(27 "Margin" user)
		(31 "F.CrtYd" user "Package Geometry/Place Bound Top")
		(29 "B.CrtYd" user "Package Geometry/Place Bound Bottom")
		(35 "F.Fab" user "Ref Des/Assembly Top")
		(33 "B.Fab" user "Ref Des/Assembly Bottom")
	)
	(footprint ""
		(layer "F.Cu")
		(at 126.0094 -68.7578 90)
		(property "Reference" "C187"
			(at 4.10083 -0.0254 0)
			(unlocked yes)
			(layer "F.SilkS")
			(effects
				(font
					(size 0.7874 0.5842)
					(thickness 0.1524)
				)
			)
		)
		(property "Value" "VAL*"
			(at 0.0762 2.067306 90)
			(unlocked yes)
			(layer "F.Fab")
			(hide yes)
			(effects
				(font
					(size 0.7874 0.5842)
					(thickness 0.1524)
				)
			)
		)
		(property "Tolerance" "TOL*"
			(at 0.0762 3.032506 90)
			(unlocked yes)
			(layer "Cmts.User")
			(hide yes)
			(effects
				(font
					(size 0.7874 0.5842)
					(thickness 0.1524)
				)
			)
		)
		(property "User Part Number" "PARTNUM*"
			(at 0.1016 4.023106 90)
			(unlocked yes)
			(layer "Cmts.User")
			(hide yes)
			(effects
				(font
					(size 0.7874 0.5842)
					(thickness 0.1524)
				)
			)
		)
		(property "Device Type" "CAPACITOR-G105-0B104-EK,0.1UF,A"
			(at 0.0508 1.127506 90)
			(unlocked yes)
			(layer "F.Fab")
			(hide yes)
			(effects
				(font
					(size 0.7874 0.5842)
					(thickness 0.1524)
				)
			)
		)
		(duplicate_pad_numbers_are_jumpers no)
		(fp_line
			(start 1.143 -0.5588)
			(end -1.143 -0.5588)
			(stroke
				(width 0.1)
				(type default)
			)
			(layer "F.SilkS")
		)
		(fp_line
			(start -1.143 -0.5588)
			(end -1.143 0.5588)
			(stroke
				(width 0.1)
				(type default)
			)
			(layer "F.SilkS")
		)
		(fp_line
			(start 1.143 0.5588)
			(end 1.143 -0.5588)
			(stroke
				(width 0.1)
				(type default)
			)
			(layer "F.SilkS")
		)
		(fp_line
			(start -1.143 0.5588)
			(end 1.143 0.5588)
			(stroke
				(width 0.1)
				(type default)
			)
			(layer "F.SilkS")
		)
		(fp_rect
			(start 1.143 0.5588)
			(end -1.143 -0.5588)
			(stroke
				(width 0)
				(type default)
			)
			(fill no)
			(layer "F.CrtYd")
		)
		(fp_line
			(start 0.508 -0.3048)
			(end -0.508 -0.3048)
			(stroke
				(width 0.1)
				(type default)
			)
			(layer "F.Fab")
		)
		(fp_line
			(start -0.508 -0.3048)
			(end -0.508 0.3048)
			(stroke
				(width 0.1)
				(type default)
			)
			(layer "F.Fab")
		)
		(fp_line
			(start 0.508 0.3048)
			(end 0.508 -0.3048)
			(stroke
				(width 0.1)
				(type default)
			)
			(layer "F.Fab")
		)
		(fp_line
			(start -0.508 0.3048)
			(end 0.508 0.3048)
			(stroke
				(width 0.1)
				(type default)
			)
			(layer "F.Fab")
		)
		(pad "1" smd rect
			(at -0.5334 0 90)
			(size 0.7112 0.6096)
			(layers "F.Cu" "F.Mask" "F.Paste")
			(net "XP1R8V_EN_R")
		)
		(pad "2" smd rect
			(at 0.5334 0 90)
			(size 0.7112 0.6096)
			(layers "F.Cu" "F.Mask" "F.Paste")
			(net "SG")
		)
		(zone
			(layer "F.Cu")
			(hatch none 0.5)
			(connect_pads
				(clearance 0)
			)
			(min_thickness 0.25)
			(keepout
				(tracks allowed)
				(vias not_allowed)
				(pads allowed)
				(copperpour not_allowed)
				(footprints allowed)
			)
			(placement
				(enabled no)
				(sheetname "")
			)
			(fill
				(thermal_gap 0.5)
				(thermal_bridge_width 0.5)
				(island_removal_mode 0)
			)
			(polygon
				(pts
					(xy 126.3142 -68.834) (xy 125.7046 -68.834) (xy 125.7046 -68.6816) (xy 126.3142 -68.6816)
				)
			)
		)
	)
	(footprint ""
		(layer "F.Cu")
		(at 80.772 -62.9666 180)
		(property "Reference" "R307"
			(at 10.287 19.41703 0)
			(unlocked yes)
			(layer "F.SilkS")
			(effects
				(font
					(size 0.7874 0.5842)
					(thickness 0.1524)
				)
			)
		)
		(property "Value" "VAL*"
			(at 0.02032 2.13233 180)
			(unlocked yes)
			(layer "F.Fab")
			(hide yes)
			(effects
				(font
					(size 0.7874 0.5842)
					(thickness 0.1524)
				)
			)
		)
		(property "Device Type" "RESISTOR-G155-11001-01,1KOHM,1%"
			(at 0.008382 1.210564 180)
			(unlocked yes)
			(layer "F.Fab")
			(hide yes)
			(effects
				(font
					(size 0.7874 0.5842)
					(thickness 0.1524)
				)
			)
		)
		(property "User Part Number" "PARTNUM*"
			(at 0.02032 4.024884 180)
			(unlocked yes)
			(layer "Cmts.User")
			(hide yes)
			(effects
				(font
					(size 0.7874 0.5842)
					(thickness 0.1524)
				)
			)
		)
		(property "Tolerance" "TOL*"
			(at 0.044704 3.05435 180)
			(unlocked yes)
			(layer "Cmts.User")
			(hide yes)
			(effects
				(font
					(size 0.7874 0.5842)
					(thickness 0.1524)
				)
			)
		)
		(duplicate_pad_numbers_are_jumpers no)
		(fp_line
			(start 1.143 0.5588)
			(end 1.143 -0.5588)
			(stroke
				(width 0.1)
				(type default)
			)
			(layer "F.SilkS")
		)
		(fp_line
			(start 1.143 -0.5588)
			(end -1.143 -0.5588)
			(stroke
				(width 0.1)
				(type default)
			)
			(layer "F.SilkS")
		)
		(fp_line
			(start -1.143 0.5588)
			(end 1.143 0.5588)
			(stroke
				(width 0.1)
				(type default)
			)
			(layer "F.SilkS")
		)
		(fp_line
			(start -1.143 -0.5588)
			(end -1.143 0.5588)
			(stroke
				(width 0.1)
				(type default)
			)
			(layer "F.SilkS")
		)
		(fp_rect
			(start 1.143 -0.5588)
			(end -1.143 0.5588)
			(stroke
				(width 0)
				(type default)
			)
			(fill no)
			(layer "F.CrtYd")
		)
		(fp_line
			(start 0.508 0.3048)
			(end 0.508 -0.3048)
			(stroke
				(width 0.1)
				(type default)
			)
			(layer "F.Fab")
		)
		(fp_line
			(start 0.508 -0.3048)
			(end -0.508 -0.3048)
			(stroke
				(width 0.1)
				(type default)
			)
			(layer "F.Fab")
		)
		(fp_line
			(start -0.508 0.3048)
			(end 0.508 0.3048)
			(stroke
				(width 0.1)
				(type default)
			)
			(layer "F.Fab")
		)
		(fp_line
			(start -0.508 -0.3048)
			(end -0.508 0.3048)
			(stroke
				(width 0.1)
				(type default)
			)
			(layer "F.Fab")
		)
		(pad "1" smd rect
			(at -0.5334 0 180)
			(size 0.7112 0.6096)
			(layers "F.Cu" "F.Mask" "F.Paste")
			(net "UNNAMED_9_BNO080LGA28_I29_CLKSE")
		)
		(pad "2" smd rect
			(at 0.5334 0 180)
			(size 0.7112 0.6096)
			(layers "F.Cu" "F.Mask" "F.Paste")
			(net "SG")
		)
		(zone
			(layer "F.Cu")
			(hatch none 0.5)
			(connect_pads
				(clearance 0)
			)
			(min_thickness 0.25)
			(keepout
				(tracks allowed)
				(vias not_allowed)
				(pads allowed)
				(copperpour not_allowed)
				(footprints allowed)
			)
			(placement
				(enabled no)
				(sheetname "")
			)
			(fill
				(thermal_gap 0.5)
				(thermal_bridge_width 0.5)
				(island_removal_mode 0)
			)
			(polygon
				(pts
					(xy 80.6958 -62.6618) (xy 80.8482 -62.6618) (xy 80.8482 -63.2714) (xy 80.6958 -63.2714)
				)
			)
		)
	)
)
